# BASEBOARD_FAB2 (Tioga Pass) — schematic netlist excerpt (pin names and nets, part order shuffled) for the footprints in the layout excerpt that follows; sources: Cadence DE-HDL packaged netlist, KiCad conversion of Wiwynn_Tioga_Pass_MB.brd

C2A2  CAP_A  47UF 4V 20% X5R  pkg 0603V  page 228 : A = PVDDQ_KLM ; B = GND
C5D58  CAP_A  22.0UF 4V 20% X6S  pkg 0603V  page 217 : A = PVDDQ_ABC ; B = GND
R8D35  RES  0.0 5% CHIP  pkg 0402  page 184 : A = SPI_PCH_TPM_CS_N ; B = SPI_PCH_TPM_CS_R_N

(kicad_pcb
	(version 20260206)
	(generator "pcbnew")
	(generator_version "10.0")
	(general
		(thickness 1.6)
		(legacy_teardrops no)
	)
	(paper "A4")
	(title_block
		(title "Wiwynn_Tioga_Pass_MB.brd")
		(comment 1 "Tioga Pass / footprints 1810-1812 of 4770")
	)
	(layers
		(0 "F.Cu" signal "TOP")
		(4 "In1.Cu" signal "L2GND")
		(6 "In2.Cu" signal "L3")
		(8 "In3.Cu" signal "L4GND")
		(10 "In4.Cu" signal "L5")
		(12 "In5.Cu" signal "L6GND")
		(14 "In6.Cu" signal "L7VCC")
		(16 "In7.Cu" signal "L8VCC")
		(18 "In8.Cu" signal "L9GND")
		(20 "In9.Cu" signal "L10")
		(22 "In10.Cu" signal "L11GND")
		(24 "In11.Cu" signal "L12")
		(26 "In12.Cu" signal "L13GND")
		(2 "B.Cu" signal "BOTTOM")
		(9 "F.Adhes" user "F.Adhesive")
		(11 "B.Adhes" user "B.Adhesive")
		(13 "F.Paste" user "Package Geometry/Pastemask Top")
		(15 "B.Paste" user "Package Geometry/Pastemask Bottom")
		(5 "F.SilkS" user "Ref Des/Silkscreen Top")
		(7 "B.SilkS" user "Ref Des/Silkscreen Bottom")
		(1 "F.Mask" user "Board Geometry/Soldermask Top")
		(3 "B.Mask" user "Board Geometry/Soldermask Bottom")
		(17 "Dwgs.User" user "User.Drawings")
		(19 "Cmts.User" user "User.Comments")
		(21 "Eco1.User" user "User.Eco1")
		(23 "Eco2.User" user "User.Eco2")
		(25 "Edge.Cuts" user "Board Geometry/Outline")
		(27 "Margin" user)
		(31 "F.CrtYd" user "Package Geometry/Place Bound Top")
		(29 "B.CrtYd" user "Package Geometry/Place Bound Bottom")
		(35 "F.Fab" user "Ref Des/Assembly Top")
		(33 "B.Fab" user "Ref Des/Assembly Bottom")
	)
	(footprint ""
		(layer "F.Cu")
		(at 406.6286 -61.6204 90)
		(property "Reference" "R8D35"
			(at 0 0 90)
			(layer "F.SilkS")
			(hide yes)
			(effects
				(font
					(size 1.27 1.27)
				)
			)
		)
		(property "Value" ""
			(at 0 0 90)
			(layer "F.Fab")
			(effects
				(font
					(size 1.27 1.27)
				)
			)
		)
		(duplicate_pad_numbers_are_jumpers no)
		(fp_poly
			(pts
				(xy -0.2794 -0.1016) (xy 0.2794 -0.1016) (xy 0.2794 0.9906) (xy -0.2794 0.9906)
			)
			(stroke
				(width 0)
				(type default)
			)
			(fill no)
			(layer "F.CrtYd")
		)
		(pad "1" smd rect
			(at 0 0 90)
			(size 0.508 0.508)
			(layers "F.Cu" "F.Mask" "F.Paste")
			(net "SPI_PCH_TPM_CS_N")
		)
		(pad "2" smd rect
			(at 0 0.889 90)
			(size 0.508 0.508)
			(layers "F.Cu" "F.Mask" "F.Paste")
			(net "SPI_PCH_TPM_CS_R_N")
		)
		(zone
			(layer "F.Cu")
			(hatch none 0.5)
			(connect_pads
				(clearance 0)
			)
			(min_thickness 0.25)
			(keepout
				(tracks allowed)
				(vias not_allowed)
				(pads allowed)
				(copperpour not_allowed)
				(footprints allowed)
			)
			(placement
				(enabled no)
				(sheetname "")
			)
			(fill
				(thermal_gap 0.5)
				(thermal_bridge_width 0.5)
				(island_removal_mode 0)
			)
			(polygon
				(pts
					(xy 406.8826 -61.3664) (xy 406.8826 -61.8744) (xy 407.2636 -61.8744) (xy 407.2636 -61.3664)
				)
			)
		)
		(zone
			(layer "F.Cu")
			(hatch none 0.5)
			(connect_pads
				(clearance 0)
			)
			(min_thickness 0.25)
			(keepout
				(tracks not_allowed)
				(vias allowed)
				(pads allowed)
				(copperpour not_allowed)
				(footprints allowed)
			)
			(placement
				(enabled no)
				(sheetname "")
			)
			(fill
				(thermal_gap 0.5)
				(thermal_bridge_width 0.5)
				(island_removal_mode 0)
			)
			(polygon
				(pts
					(xy 407.2636 -61.3664) (xy 407.2636 -61.8744) (xy 406.8826 -61.8744) (xy 406.8826 -61.3664)
				)
			)
		)
	)
	(footprint ""
		(layer "F.Cu")
		(at 83.856068 -149.8092 -90)
		(property "Reference" "C2A2"
			(at 1.848866 0.752348 270)
			(unlocked yes)
			(layer "F.SilkS")
			(effects
				(font
					(size 1.27 0.9652)
					(thickness 0.1524)
				)
			)
		)
		(property "Value" ""
			(at 0 0 270)
			(layer "F.Fab")
			(effects
				(font
					(size 1.27 1.27)
				)
			)
		)
		(duplicate_pad_numbers_are_jumpers no)
		(fp_rect
			(start -0.500126 1.598422)
			(end 0.500126 -0.201422)
			(stroke
				(width 0)
				(type default)
			)
			(fill no)
			(layer "F.CrtYd")
		)
		(fp_line
			(start -0.500126 1.598422)
			(end -0.500126 -0.201422)
			(stroke
				(width 0.1)
				(type default)
			)
			(layer "F.Fab")
		)
		(fp_line
			(start 0.500126 1.598422)
			(end -0.500126 1.598422)
			(stroke
				(width 0.1)
				(type default)
			)
			(layer "F.Fab")
		)
		(fp_line
			(start -0.500126 -0.201422)
			(end 0.500126 -0.201422)
			(stroke
				(width 0.1)
				(type default)
			)
			(layer "F.Fab")
		)
		(fp_line
			(start 0.500126 -0.201422)
			(end 0.500126 1.598422)
			(stroke
				(width 0.1)
				(type default)
			)
			(layer "F.Fab")
		)
		(pad "1" smd rect
			(at 0 0 180)
			(size 0.889 0.9906)
			(layers "F.Cu" "F.Mask" "F.Paste")
			(net "PVDDQ_KLM")
		)
		(pad "2" smd rect
			(at 0 1.397 180)
			(size 0.889 0.9906)
			(layers "F.Cu" "F.Mask" "F.Paste")
			(net "GND")
		)
		(zone
			(layer "F.Cu")
			(hatch none 0.5)
			(connect_pads
				(clearance 0)
			)
			(min_thickness 0.25)
			(keepout
				(tracks not_allowed)
				(vias allowed)
				(pads allowed)
				(copperpour not_allowed)
				(footprints allowed)
			)
			(placement
				(enabled no)
				(sheetname "")
			)
			(fill
				(thermal_gap 0.5)
				(thermal_bridge_width 0.5)
				(island_removal_mode 0)
			)
			(polygon
				(pts
					(xy 82.903568 -150.3045) (xy 82.903568 -149.3139) (xy 83.411568 -149.3139) (xy 83.411568 -150.3045)
				)
			)
		)
		(zone
			(layer "F.Cu")
			(hatch none 0.5)
			(connect_pads
				(clearance 0)
			)
			(min_thickness 0.25)
			(keepout
				(tracks allowed)
				(vias not_allowed)
				(pads allowed)
				(copperpour not_allowed)
				(footprints allowed)
			)
			(placement
				(enabled no)
				(sheetname "")
			)
			(fill
				(thermal_gap 0.5)
				(thermal_bridge_width 0.5)
				(island_removal_mode 0)
			)
			(polygon
				(pts
					(xy 82.903568 -150.3045) (xy 82.903568 -149.3139) (xy 83.411568 -149.3139) (xy 83.411568 -150.3045)
				)
			)
		)
	)
	(footprint ""
		(layer "F.Cu")
		(at 268.401038 -68.365116 180)
		(property "Reference" "C5D58"
			(at 0 0 180)
			(layer "F.SilkS")
			(hide yes)
			(effects
				(font
					(size 1.27 1.27)
				)
			)
		)
		(property "Value" ""
			(at 0 0 180)
			(layer "F.Fab")
			(effects
				(font
					(size 1.27 1.27)
				)
			)
		)
		(duplicate_pad_numbers_are_jumpers no)
		(fp_poly
			(pts
				(xy -0.4953 -0.2032) (xy 0.4953 -0.2032) (xy 0.4953 1.6002) (xy -0.4953 1.6002)
			)
			(stroke
				(width 0)
				(type default)
			)
			(fill no)
			(layer "F.CrtYd")
		)
		(fp_line
			(start 0.4953 1.6002)
			(end -0.4953 1.6002)
			(stroke
				(width 0.1)
				(type default)
			)
			(layer "F.Fab")
		)
		(fp_line
			(start 0.4953 -0.2032)
			(end 0.4953 1.6002)
			(stroke
				(width 0.1)
				(type default)
			)
			(layer "F.Fab")
		)
		(fp_line
			(start -0.4953 1.6002)
			(end -0.4953 -0.2032)
			(stroke
				(width 0.1)
				(type default)
			)
			(layer "F.Fab")
		)
		(fp_line
			(start -0.4953 -0.2032)
			(end 0.4953 -0.2032)
			(stroke
				(width 0.1)
				(type default)
			)
			(layer "F.Fab")
		)
		(pad "1" smd rect
			(at 0 0 180)
			(size 0.762 0.889)
			(layers "F.Cu" "F.Mask" "F.Paste")
			(net "PVDDQ_ABC")
		)
		(pad "2" smd rect
			(at 0 1.397 180)
			(size 0.762 0.889)
			(layers "F.Cu" "F.Mask" "F.Paste")
			(net "GND")
		)
		(zone
			(layer "F.Cu")
			(hatch none 0.5)
			(connect_pads
				(clearance 0)
			)
			(min_thickness 0.25)
			(keepout
				(tracks not_allowed)
				(vias allowed)
				(pads allowed)
				(copperpour not_allowed)
				(footprints allowed)
			)
			(placement
				(enabled no)
				(sheetname "")
			)
			(fill
				(thermal_gap 0.5)
				(thermal_bridge_width 0.5)
				(island_removal_mode 0)
			)
			(polygon
				(pts
					(xy 268.782038 -68.809616) (xy 268.020038 -68.809616) (xy 268.020038 -69.317616) (xy 268.782038 -69.317616)
				)
			)
		)
	)
)
